(kicad_pcb
	(version 20260206)
	(generator "pcbnew")
	(generator_version "10.0")
	(general
		(thickness 1.6)
		(legacy_teardrops no)
	)
	(paper "A4")
	(title_block
		(title "Bryce Canyon_IOM_IOC_16318-2_OCP.brd")
		(comment 1 "Bryce Canyon / footprint 367 of 1605 (U2), pads 228-345 of 456")
	)
	(layers
		(0 "F.Cu" signal "TOP")
		(4 "In1.Cu" signal "L2GND")
		(6 "In2.Cu" signal "L3")
		(8 "In3.Cu" signal "L4VCC")
		(10 "In4.Cu" signal "L5VCC")
		(12 "In5.Cu" signal "L6")
		(14 "In6.Cu" signal "L7GND")
		(2 "B.Cu" signal "BOTTOM")
		(9 "F.Adhes" user "F.Adhesive")
		(11 "B.Adhes" user "B.Adhesive")
		(13 "F.Paste" user "Package Geometry/Pastemask Top")
		(15 "B.Paste" user "Package Geometry/Pastemask Bottom")
		(5 "F.SilkS" user "Ref Des/Silkscreen Top")
		(7 "B.SilkS" user "Ref Des/Silkscreen Bottom")
		(1 "F.Mask" user "Board Geometry/Soldermask Top")
		(3 "B.Mask" user "Board Geometry/Soldermask Bottom")
		(17 "Dwgs.User" user "User.Drawings")
		(19 "Cmts.User" user "User.Comments")
		(21 "Eco1.User" user "User.Eco1")
		(23 "Eco2.User" user "User.Eco2")
		(25 "Edge.Cuts" user "Board Geometry/Outline")
		(27 "Margin" user)
		(31 "F.CrtYd" user "Package Geometry/Place Bound Top")
		(29 "B.CrtYd" user "Package Geometry/Place Bound Bottom")
		(35 "F.Fab" user "Ref Des/Assembly Top")
		(33 "B.Fab" user "Ref Des/Assembly Bottom")
	)
	(footprint ""
		(layer "F.Cu")
		(at 47.69993 -144.999964 -90)
		(property "Reference" "U2"
			(at 0 0 270)
			(layer "F.SilkS")
			(hide yes)
			(effects
				(font
					(size 1.27 1.27)
				)
			)
		)
		(property "Value" "AST2500A2-GP-GP-U"
			(at -17.0307 -8.584692 270)
			(unlocked yes)
			(layer "F.Fab")
			(hide yes)
			(effects
				(font
					(size 1.016 1.016)
					(thickness 0.1524)
				)
			)
		)
		(property "Device Type" "BGA456D19H58"
			(at -17.0307 -10.108692 270)
			(unlocked yes)
			(layer "F.Fab")
			(hide yes)
			(effects
				(font
					(size 1.016 1.016)
					(thickness 0.1524)
				)
			)
		)
		(duplicate_pad_numbers_are_jumpers no)
		(pad "J18" smd circle
			(at 5.199888 -1.999996 270)
			(size 0.3556 0.3556)
			(layers "F.Cu" "F.Mask" "F.Paste")
			(net "SCC_RMT_FULLPWR_EN")
		)
		(pad "J19" smd circle
			(at 5.999988 -1.999996 270)
			(size 0.3556 0.3556)
			(layers "F.Cu" "F.Mask" "F.Paste")
			(net "SCC_LOC_FULLPWR_EN")
		)
		(pad "J20" smd circle
			(at 6.800088 -1.999996 270)
			(size 0.3556 0.3556)
			(layers "F.Cu" "F.Mask" "F.Paste")
			(net "TP_M2_1_ALERT#")
		)
		(pad "J21" smd circle
			(at 7.599934 -1.999996 270)
			(size 0.3556 0.3556)
			(layers "F.Cu" "F.Mask" "F.Paste")
			(net "GND")
		)
		(pad "J22" smd circle
			(at 8.400034 -1.999996 270)
			(size 0.3556 0.3556)
			(layers "F.Cu" "F.Mask" "F.Paste")
			(net "GND")
		)
		(pad "K1" smd circle
			(at -8.400034 -1.199896 270)
			(size 0.3556 0.3556)
			(layers "F.Cu" "F.Mask" "F.Paste")
			(net "UART_BMC_R_TX")
		)
		(pad "K2" smd circle
			(at -7.599934 -1.199896 270)
			(size 0.3556 0.3556)
			(layers "F.Cu" "F.Mask" "F.Paste")
			(net "UART_BMC_R_RX")
		)
		(pad "K3" smd circle
			(at -6.800088 -1.199896 270)
			(size 0.3556 0.3556)
			(layers "F.Cu" "F.Mask" "F.Paste")
			(net "BMC_ENTEST")
		)
		(pad "K4" smd circle
			(at -5.999988 -1.199896 270)
			(size 0.3556 0.3556)
			(layers "F.Cu" "F.Mask" "F.Paste")
			(net "DACRSET")
		)
		(pad "K5" smd circle
			(at -5.199888 -1.199896 270)
			(size 0.3556 0.3556)
			(layers "F.Cu" "F.Mask" "F.Paste")
			(net "DACAV33")
		)
		(pad "K6" smd circle
			(at -4.400042 -1.199896 270)
			(size 0.3556 0.3556)
			(layers "F.Cu" "F.Mask" "F.Paste")
			(net "DACAV33")
		)
		(pad "K7" smd circle
			(at -3.599942 -1.199896 270)
			(size 0.3556 0.3556)
			(layers "F.Cu" "F.Mask" "F.Paste")
			(net "P3V3_STBY")
		)
		(pad "K9" smd circle
			(at -1.999996 -1.199896 270)
			(size 0.3556 0.3556)
			(layers "F.Cu" "F.Mask" "F.Paste")
			(net "GND")
		)
		(pad "K10" smd circle
			(at -1.199896 -1.199896 270)
			(size 0.3556 0.3556)
			(layers "F.Cu" "F.Mask" "F.Paste")
			(net "GND")
		)
		(pad "K11" smd circle
			(at -0.40005 -1.199896 270)
			(size 0.3556 0.3556)
			(layers "F.Cu" "F.Mask" "F.Paste")
			(net "GND")
		)
		(pad "K12" smd circle
			(at 0.40005 -1.199896 270)
			(size 0.3556 0.3556)
			(layers "F.Cu" "F.Mask" "F.Paste")
			(net "GND")
		)
		(pad "K13" smd circle
			(at 1.199896 -1.199896 270)
			(size 0.3556 0.3556)
			(layers "F.Cu" "F.Mask" "F.Paste")
			(net "GND")
		)
		(pad "K14" smd circle
			(at 1.999996 -1.199896 270)
			(size 0.3556 0.3556)
			(layers "F.Cu" "F.Mask" "F.Paste")
			(net "GND")
		)
		(pad "K16" smd circle
			(at 3.599942 -1.199896 270)
			(size 0.3556 0.3556)
			(layers "F.Cu" "F.Mask" "F.Paste")
			(net "GND")
		)
		(pad "K17" smd circle
			(at 4.400042 -1.199896 270)
			(size 0.3556 0.3556)
			(layers "F.Cu" "F.Mask" "F.Paste")
			(net "P1V8_STBY")
		)
		(pad "K18" smd circle
			(at 5.199888 -1.199896 270)
			(size 0.3556 0.3556)
			(layers "F.Cu" "F.Mask" "F.Paste")
			(net "Net_653")
		)
		(pad "K19" smd circle
			(at 5.999988 -1.199896 270)
			(size 0.3556 0.3556)
			(layers "F.Cu" "F.Mask" "F.Paste")
			(net "Net_652")
		)
		(pad "K20" smd circle
			(at 6.800088 -1.199896 270)
			(size 0.3556 0.3556)
			(layers "F.Cu" "F.Mask" "F.Paste")
			(net "BMC_PEREXT")
		)
		(pad "K21" smd circle
			(at 7.599934 -1.199896 270)
			(size 0.3556 0.3556)
			(layers "F.Cu" "F.Mask" "F.Paste")
			(net "GND")
		)
		(pad "K22" smd circle
			(at 8.400034 -1.199896 270)
			(size 0.3556 0.3556)
			(layers "F.Cu" "F.Mask" "F.Paste")
			(net "GND")
		)
		(pad "L1" smd circle
			(at -8.400034 -0.40005 270)
			(size 0.3556 0.3556)
			(layers "F.Cu" "F.Mask" "F.Paste")
			(net "BMC_SMB6_CLK")
		)
		(pad "L2" smd circle
			(at -7.599934 -0.40005 270)
			(size 0.3556 0.3556)
			(layers "F.Cu" "F.Mask" "F.Paste")
			(net "BOARD_REV_1")
		)
		(pad "L3" smd circle
			(at -6.800088 -0.40005 270)
			(size 0.3556 0.3556)
			(layers "F.Cu" "F.Mask" "F.Paste")
			(net "BMC_SMB5_CLK")
		)
		(pad "L4" smd circle
			(at -5.999988 -0.40005 270)
			(size 0.3556 0.3556)
			(layers "F.Cu" "F.Mask" "F.Paste")
			(net "BMC_SMB5_DAT")
		)
		(pad "L5" smd circle
			(at -5.199888 -0.40005 270)
			(size 0.3556 0.3556)
			(layers "F.Cu" "F.Mask" "F.Paste")
			(net "V1PLLAV11")
		)
		(pad "L6" smd circle
			(at -4.400042 -0.40005 270)
			(size 0.3556 0.3556)
			(layers "F.Cu" "F.Mask" "F.Paste")
			(net "V1PLLAV11")
		)
		(pad "L7" smd circle
			(at -3.599942 -0.40005 270)
			(size 0.3556 0.3556)
			(layers "F.Cu" "F.Mask" "F.Paste")
			(net "P1V15_STBY")
		)
		(pad "L9" smd circle
			(at -1.999996 -0.40005 270)
			(size 0.3556 0.3556)
			(layers "F.Cu" "F.Mask" "F.Paste")
			(net "GND")
		)
		(pad "L10" smd circle
			(at -1.199896 -0.40005 270)
			(size 0.3556 0.3556)
			(layers "F.Cu" "F.Mask" "F.Paste")
			(net "GND")
		)
		(pad "L11" smd circle
			(at -0.40005 -0.40005 270)
			(size 0.3556 0.3556)
			(layers "F.Cu" "F.Mask" "F.Paste")
			(net "GND")
		)
		(pad "L12" smd circle
			(at 0.40005 -0.40005 270)
			(size 0.3556 0.3556)
			(layers "F.Cu" "F.Mask" "F.Paste")
			(net "GND")
		)
		(pad "L13" smd circle
			(at 1.199896 -0.40005 270)
			(size 0.3556 0.3556)
			(layers "F.Cu" "F.Mask" "F.Paste")
			(net "GND")
		)
		(pad "L14" smd circle
			(at 1.999996 -0.40005 270)
			(size 0.3556 0.3556)
			(layers "F.Cu" "F.Mask" "F.Paste")
			(net "GND")
		)
		(pad "L16" smd circle
			(at 3.599942 -0.40005 270)
			(size 0.3556 0.3556)
			(layers "F.Cu" "F.Mask" "F.Paste")
			(net "P3V3_STBY")
		)
		(pad "L17" smd circle
			(at 4.400042 -0.40005 270)
			(size 0.3556 0.3556)
			(layers "F.Cu" "F.Mask" "F.Paste")
			(net "P1V15_STBY")
		)
		(pad "L18" smd circle
			(at 5.199888 -0.40005 270)
			(size 0.3556 0.3556)
			(layers "F.Cu" "F.Mask" "F.Paste")
			(net "Net_651")
		)
		(pad "L19" smd circle
			(at 5.999988 -0.40005 270)
			(size 0.3556 0.3556)
			(layers "F.Cu" "F.Mask" "F.Paste")
			(net "Net_650")
		)
		(pad "L20" smd circle
			(at 6.800088 -0.40005 270)
			(size 0.3556 0.3556)
			(layers "F.Cu" "F.Mask" "F.Paste")
			(net "PD_PERST_N")
		)
		(pad "L21" smd circle
			(at 7.599934 -0.40005 270)
			(size 0.3556 0.3556)
			(layers "F.Cu" "F.Mask" "F.Paste")
			(net "Net_649")
		)
		(pad "L22" smd circle
			(at 8.400034 -0.40005 270)
			(size 0.3556 0.3556)
			(layers "F.Cu" "F.Mask" "F.Paste")
			(net "Net_648")
		)
		(pad "M1" smd circle
			(at -8.400034 0.40005 270)
			(size 0.3556 0.3556)
			(layers "F.Cu" "F.Mask" "F.Paste")
			(net "GND")
		)
		(pad "M2" smd circle
			(at -7.599934 0.40005 270)
			(size 0.3556 0.3556)
			(layers "F.Cu" "F.Mask" "F.Paste")
			(net "GND")
		)
		(pad "M3" smd circle
			(at -6.800088 0.40005 270)
			(size 0.3556 0.3556)
			(layers "F.Cu" "F.Mask" "F.Paste")
			(net "GND")
		)
		(pad "M4" smd circle
			(at -5.999988 0.40005 270)
			(size 0.3556 0.3556)
			(layers "F.Cu" "F.Mask" "F.Paste")
			(net "GND")
		)
		(pad "M5" smd circle
			(at -5.199888 0.40005 270)
			(size 0.3556 0.3556)
			(layers "F.Cu" "F.Mask" "F.Paste")
			(net "GND")
		)
		(pad "M6" smd circle
			(at -4.400042 0.40005 270)
			(size 0.3556 0.3556)
			(layers "F.Cu" "F.Mask" "F.Paste")
			(net "GND")
		)
		(pad "M7" smd circle
			(at -3.599942 0.40005 270)
			(size 0.3556 0.3556)
			(layers "F.Cu" "F.Mask" "F.Paste")
			(net "GND")
		)
		(pad "M9" smd circle
			(at -1.999996 0.40005 270)
			(size 0.3556 0.3556)
			(layers "F.Cu" "F.Mask" "F.Paste")
			(net "GND")
		)
		(pad "M10" smd circle
			(at -1.199896 0.40005 270)
			(size 0.3556 0.3556)
			(layers "F.Cu" "F.Mask" "F.Paste")
			(net "GND")
		)
		(pad "M11" smd circle
			(at -0.40005 0.40005 270)
			(size 0.3556 0.3556)
			(layers "F.Cu" "F.Mask" "F.Paste")
			(net "GND")
		)
		(pad "M12" smd circle
			(at 0.40005 0.40005 270)
			(size 0.3556 0.3556)
			(layers "F.Cu" "F.Mask" "F.Paste")
			(net "GND")
		)
		(pad "M13" smd circle
			(at 1.199896 0.40005 270)
			(size 0.3556 0.3556)
			(layers "F.Cu" "F.Mask" "F.Paste")
			(net "GND")
		)
		(pad "M14" smd circle
			(at 1.999996 0.40005 270)
			(size 0.3556 0.3556)
			(layers "F.Cu" "F.Mask" "F.Paste")
			(net "GND")
		)
		(pad "M16" smd circle
			(at 3.599942 0.40005 270)
			(size 0.3556 0.3556)
			(layers "F.Cu" "F.Mask" "F.Paste")
			(net "GND")
		)
		(pad "M17" smd circle
			(at 4.400042 0.40005 270)
			(size 0.3556 0.3556)
			(layers "F.Cu" "F.Mask" "F.Paste")
			(net "GND")
		)
		(pad "M18" smd circle
			(at 5.199888 0.40005 270)
			(size 0.3556 0.3556)
			(layers "F.Cu" "F.Mask" "F.Paste")
			(net "BMC_SMB1_CLK")
		)
		(pad "M19" smd circle
			(at 5.999988 0.40005 270)
			(size 0.3556 0.3556)
			(layers "F.Cu" "F.Mask" "F.Paste")
			(net "BMC_SMB1_DAT")
		)
		(pad "M20" smd circle
			(at 6.800088 0.40005 270)
			(size 0.3556 0.3556)
			(layers "F.Cu" "F.Mask" "F.Paste")
			(net "BMC_SMB2_CLK")
		)
		(pad "M21" smd circle
			(at 7.599934 0.40005 270)
			(size 0.3556 0.3556)
			(layers "F.Cu" "F.Mask" "F.Paste")
			(net "GND")
		)
		(pad "M22" smd circle
			(at 8.400034 0.40005 270)
			(size 0.3556 0.3556)
			(layers "F.Cu" "F.Mask" "F.Paste")
			(net "GND")
		)
		(pad "N1" smd circle
			(at -8.400034 1.199896 270)
			(size 0.3556 0.3556)
			(layers "F.Cu" "F.Mask" "F.Paste")
			(net "BMC_SMB7_CLK")
		)
		(pad "N2" smd circle
			(at -7.599934 1.199896 270)
			(size 0.3556 0.3556)
			(layers "F.Cu" "F.Mask" "F.Paste")
			(net "BMC_SMB6_DAT")
		)
		(pad "N3" smd circle
			(at -6.800088 1.199896 270)
			(size 0.3556 0.3556)
			(layers "F.Cu" "F.Mask" "F.Paste")
			(net "BOARD_REV_2")
		)
		(pad "N4" smd circle
			(at -5.999988 1.199896 270)
			(size 0.3556 0.3556)
			(layers "F.Cu" "F.Mask" "F.Paste")
			(net "PCIE_WAKE_N")
		)
		(pad "N5" smd circle
			(at -5.199888 1.199896 270)
			(size 0.3556 0.3556)
			(layers "F.Cu" "F.Mask" "F.Paste")
			(net "IOM_TYPE0")
		)
		(pad "N6" smd circle
			(at -4.400042 1.199896 270)
			(size 0.3556 0.3556)
			(layers "F.Cu" "F.Mask" "F.Paste")
			(net "P3V3_STBY")
		)
		(pad "N7" smd circle
			(at -3.599942 1.199896 270)
			(size 0.3556 0.3556)
			(layers "F.Cu" "F.Mask" "F.Paste")
			(net "P1V15_STBY")
		)
		(pad "N9" smd circle
			(at -1.999996 1.199896 270)
			(size 0.3556 0.3556)
			(layers "F.Cu" "F.Mask" "F.Paste")
			(net "GND")
		)
		(pad "N10" smd circle
			(at -1.199896 1.199896 270)
			(size 0.3556 0.3556)
			(layers "F.Cu" "F.Mask" "F.Paste")
			(net "GND")
		)
		(pad "N11" smd circle
			(at -0.40005 1.199896 270)
			(size 0.3556 0.3556)
			(layers "F.Cu" "F.Mask" "F.Paste")
			(net "GND")
		)
		(pad "N12" smd circle
			(at 0.40005 1.199896 270)
			(size 0.3556 0.3556)
			(layers "F.Cu" "F.Mask" "F.Paste")
			(net "GND")
		)
		(pad "N13" smd circle
			(at 1.199896 1.199896 270)
			(size 0.3556 0.3556)
			(layers "F.Cu" "F.Mask" "F.Paste")
			(net "GND")
		)
		(pad "N14" smd circle
			(at 1.999996 1.199896 270)
			(size 0.3556 0.3556)
			(layers "F.Cu" "F.Mask" "F.Paste")
			(net "GND")
		)
		(pad "N16" smd circle
			(at 3.599942 1.199896 270)
			(size 0.3556 0.3556)
			(layers "F.Cu" "F.Mask" "F.Paste")
			(net "P1V15_STBY")
		)
		(pad "N17" smd circle
			(at 4.400042 1.199896 270)
			(size 0.3556 0.3556)
			(layers "F.Cu" "F.Mask" "F.Paste")
			(net "P3V3_STBY")
		)
		(pad "N18" smd circle
			(at 5.199888 1.199896 270)
			(size 0.3556 0.3556)
			(layers "F.Cu" "F.Mask" "F.Paste")
			(net "I2C_MEZZ_ALERT_N")
		)
		(pad "N19" smd circle
			(at 5.999988 1.199896 270)
			(size 0.3556 0.3556)
			(layers "F.Cu" "F.Mask" "F.Paste")
			(net "IOM_LOC_INS_N")
		)
		(pad "N20" smd circle
			(at 6.800088 1.199896 270)
			(size 0.3556 0.3556)
			(layers "F.Cu" "F.Mask" "F.Paste")
			(net "Net_647")
		)
		(pad "N21" smd circle
			(at 7.599934 1.199896 270)
			(size 0.3556 0.3556)
			(layers "F.Cu" "F.Mask" "F.Paste")
			(net "BMC_SMB14_CLK")
		)
		(pad "N22" smd circle
			(at 8.400034 1.199896 270)
			(size 0.3556 0.3556)
			(layers "F.Cu" "F.Mask" "F.Paste")
			(net "BMC_SMB14_DAT")
		)
		(pad "P1" smd circle
			(at -8.400034 1.999996 270)
			(size 0.3556 0.3556)
			(layers "F.Cu" "F.Mask" "F.Paste")
			(net "BMC_SMB7_DAT")
		)
		(pad "P2" smd circle
			(at -7.599934 1.999996 270)
			(size 0.3556 0.3556)
			(layers "F.Cu" "F.Mask" "F.Paste")
			(net "BMC_SMB8_CLK")
		)
		(pad "P3" smd circle
			(at -6.800088 1.999996 270)
			(size 0.3556 0.3556)
			(layers "F.Cu" "F.Mask" "F.Paste")
			(net "TP_BMC_GPIOL5")
		)
		(pad "P4" smd circle
			(at -5.999988 1.999996 270)
			(size 0.3556 0.3556)
			(layers "F.Cu" "F.Mask" "F.Paste")
			(net "TP_BMC_GPIOL4")
		)
		(pad "P5" smd circle
			(at -5.199888 1.999996 270)
			(size 0.3556 0.3556)
			(layers "F.Cu" "F.Mask" "F.Paste")
			(net "Net_287")
		)
		(pad "P6" smd circle
			(at -4.400042 1.999996 270)
			(size 0.3556 0.3556)
			(layers "F.Cu" "F.Mask" "F.Paste")
			(net "P3V3_STBY")
		)
		(pad "P7" smd circle
			(at -3.599942 1.999996 270)
			(size 0.3556 0.3556)
			(layers "F.Cu" "F.Mask" "F.Paste")
			(net "P1V15_STBY")
		)
		(pad "P9" smd circle
			(at -1.999996 1.999996 270)
			(size 0.3556 0.3556)
			(layers "F.Cu" "F.Mask" "F.Paste")
			(net "P1V15_STBY")
		)
		(pad "P10" smd circle
			(at -1.199896 1.999996 270)
			(size 0.3556 0.3556)
			(layers "F.Cu" "F.Mask" "F.Paste")
			(net "P1V15_STBY")
		)
		(pad "P11" smd circle
			(at -0.40005 1.999996 270)
			(size 0.3556 0.3556)
			(layers "F.Cu" "F.Mask" "F.Paste")
			(net "P1V15_STBY")
		)
		(pad "P12" smd circle
			(at 0.40005 1.999996 270)
			(size 0.3556 0.3556)
			(layers "F.Cu" "F.Mask" "F.Paste")
			(net "P1V15_STBY")
		)
		(pad "P13" smd circle
			(at 1.199896 1.999996 270)
			(size 0.3556 0.3556)
			(layers "F.Cu" "F.Mask" "F.Paste")
			(net "P1V15_STBY")
		)
		(pad "P14" smd circle
			(at 1.999996 1.999996 270)
			(size 0.3556 0.3556)
			(layers "F.Cu" "F.Mask" "F.Paste")
			(net "P1V15_STBY")
		)
		(pad "P16" smd circle
			(at 3.599942 1.999996 270)
			(size 0.3556 0.3556)
			(layers "F.Cu" "F.Mask" "F.Paste")
			(net "P1V15_STBY")
		)
		(pad "P17" smd circle
			(at 4.400042 1.999996 270)
			(size 0.3556 0.3556)
			(layers "F.Cu" "F.Mask" "F.Paste")
			(net "P3V3_STBY")
		)
		(pad "P18" smd circle
			(at 5.199888 1.999996 270)
			(size 0.3556 0.3556)
			(layers "F.Cu" "F.Mask" "F.Paste")
			(net "Net_20")
		)
		(pad "P19" smd circle
			(at 5.999988 1.999996 270)
			(size 0.3556 0.3556)
			(layers "F.Cu" "F.Mask" "F.Paste")
			(net "IOM_FULL_PWR_EN_R")
		)
		(pad "P20" smd circle
			(at 6.800088 1.999996 270)
			(size 0.3556 0.3556)
			(layers "F.Cu" "F.Mask" "F.Paste")
			(net "BMC_SMB2_DAT")
		)
		(pad "P21" smd circle
			(at 7.599934 1.999996 270)
			(size 0.3556 0.3556)
			(layers "F.Cu" "F.Mask" "F.Paste")
			(net "BMC_GPIOY3")
		)
		(pad "P22" smd circle
			(at 8.400034 1.999996 270)
			(size 0.3556 0.3556)
			(layers "F.Cu" "F.Mask" "F.Paste")
			(net "BMC_GPIOY2")
		)
		(pad "R1" smd circle
			(at -8.400034 2.800096 270)
			(size 0.3556 0.3556)
			(layers "F.Cu" "F.Mask" "F.Paste")
			(net "BMC_SMB8_DAT")
		)
		(pad "R2" smd circle
			(at -7.599934 2.800096 270)
			(size 0.3556 0.3556)
			(layers "F.Cu" "F.Mask" "F.Paste")
			(net "BOARD_REV_0")
		)
		(pad "R3" smd circle
			(at -6.800088 2.800096 270)
			(size 0.3556 0.3556)
			(layers "F.Cu" "F.Mask" "F.Paste")
			(net "IOM_TYPE2")
		)
		(pad "R4" smd circle
			(at -5.999988 2.800096 270)
			(size 0.3556 0.3556)
			(layers "F.Cu" "F.Mask" "F.Paste")
			(net "IOM_TYPE1")
		)
		(pad "R5" smd circle
			(at -5.199888 2.800096 270)
			(size 0.3556 0.3556)
			(layers "F.Cu" "F.Mask" "F.Paste")
			(net "UART_EXP_BMC_RX_R")
		)
		(pad "R6" smd circle
			(at -4.400042 2.800096 270)
			(size 0.3556 0.3556)
			(layers "F.Cu" "F.Mask" "F.Paste")
			(net "P3V3_STBY")
		)
		(pad "R7" smd circle
			(at -3.599942 2.800096 270)
			(size 0.3556 0.3556)
			(layers "F.Cu" "F.Mask" "F.Paste")
			(net "P1V15_STBY")
		)
		(pad "R16" smd circle
			(at 3.599942 2.800096 270)
			(size 0.3556 0.3556)
			(layers "F.Cu" "F.Mask" "F.Paste")
			(net "P1V15_STBY")
		)
		(pad "R17" smd circle
			(at 4.400042 2.800096 270)
			(size 0.3556 0.3556)
			(layers "F.Cu" "F.Mask" "F.Paste")
			(net "P3V3_STBY")
		)
		(pad "R18" smd circle
			(at 5.199888 2.800096 270)
			(size 0.3556 0.3556)
			(layers "F.Cu" "F.Mask" "F.Paste")
			(net "BMC_UART_SEL_IN")
		)
		(pad "R19" smd circle
			(at 5.999988 2.800096 270)
			(size 0.3556 0.3556)
			(layers "F.Cu" "F.Mask" "F.Paste")
			(net "BMC_GPIOS4")
		)
		(pad "R20" smd circle
			(at 6.800088 2.800096 270)
			(size 0.3556 0.3556)
			(layers "F.Cu" "F.Mask" "F.Paste")
			(net "Net_121")
		)
		(pad "R21" smd circle
			(at 7.599934 2.800096 270)
			(size 0.3556 0.3556)
			(layers "F.Cu" "F.Mask" "F.Paste")
			(net "BMC_GPIOY1")
		)
	)
)
